# GPS_MODULE_ZED-F9T-00B_BOM_smb_ver.xlsx — GPS_MODULE_ZED-F9T-00B_BOM (bom)
| Designator | Quantity | Manufacturer | Manufacturer 1 | Manufacturer Part Number | Manufacturer Part Number 1 | Supplier 1 | Supplier Part Number 1 | Description | Case/Package |
| C1, C2, C3, C4, C5 | 5 | Murata |  | GRM155R61E105KA12D |  | Digikey | 490-10017-1-ND | CAP, CER, X5R, 1UF, 10%, 25V, 0402, 0.55MM T | 0402 (1005 Metric) |
| C6, C7, C8, C9 | 4 |  | Taiyo Yuden |  | UMK105BJ104KV-F | Farnell | 2779049 | None | 0402 |
| C10 | 1 |  | Murata |  | GRM033R71C103KE14D | Farnell | 2990695 | Chip Multilayer Ceramic Capacitors for General Purpose, 0201, 10000pF, X7R, 15%, 10%, 16V |  |
| D1 | 1 | Littelfuse Inc. | Littelfuse | PESD0402-140 | PESD0402-140 | Future Electronics | 1128358 | TVS DIODE 14V 40V 0402 |  |
| DS1, DS2, DS3 | 3 | Lumex Opto/Components Inc. |  | SML-LXFM0603SUGCTR |  | Digikey | 67-2320-1-ND | LED, GREEN, 574NM, 20MA, 20MCD MIN, 2.5VF MAX, 0603, 1.10MM T | 0603 (1608 Metric) |
| J1 | 1 | Sullins | Sullins | NRPN042MAMS-RC | NRPN042MAMS-RC | Digi-Key | S6009-04-ND | Dual Row 8 Position 2 mm Pitch Surface Mount Header |  |
| J2 | 1 | Bel Cinch | Bel Cinch | 142-0711-301 | 142-0711-301 | Digi-Key | J717-ND | Rf Coaxial Board Mount Connector | SMB |
| L1 | 1 |  | Murata |  | LQG15HS47NJ02D | Future Electronics | 1091743 | Multilayer type RF Inductor 47nH ±5% 0.72Ω 300mA 0402 | 0402 |
| Q1 | 1 | onsemi |  | NTR2101PT1G |  | Digikey | NTR2101PT1GOSCT-ND | MOSFET, P-CH, 8VDS, 3.7A ID, 0.052 OHM RDS(ON)@4.5VGS/3.5A, SOT-23-3 | TO-236-3, SC-59, SOT-23-3 |
| R1, R2, R3, R10, R13, R14 | 6 |  | Stackpole Electronics |  | RMCF0402FT1K00 | Future Electronics | 6297634 | 1kΩ ±1% 0.063W 0402 Thick Film Chip Resistor AEC-Q200 compliant | 0402 |
| R4, R7, R8 | 3 |  | Stackpole Electronics |  | RMCF0402FT10K0 | Future Electronics | 1731694 | 10kΩ ±1% 0.063W 0402 Thick Film Chip Resistor AEC-Q200 compliant | 0402 |
| R9, R11 | 2 |  | Stackpole Electronics |  | RMCF0402FT100K | Future Electronics | 8519472 | 100kΩ ±1% 0.063W 0402 Thick Film Chip Resistor AEC-Q200 compliant | 0402 |
| R12 | 1 | Vishay |  | RCP0603W25R0GEB |  | Digikey | 541-2654-1-ND | RES, 25 OHM, 2%, 1.5W, 150PPM/C, 0603 | 0603 (1608 Metric) |
| U1 | 1 | u-blox | u-blox | ZED-F9T-00B | ZED-F9T-00B | Digi-Key | 672-1197-1-ND | Multi-band GNSS Receiver with Nanosecond-level Timing Accuracy | SMD/SMT |
| U2, U3 | 2 | Texas Instruments | Texas Instruments |  | SN74LVC3G07DCUR | Farnell | 2460000 | Triple Buffer/Driver With Open-Drain Output, DCU0008A, LARGE T&R |  |
| U4 | 1 | Texas Instruments | TI National Semiconductor |  | LPV511MGX/NOPB | Digi-Key | 296-44295-1-ND | micropower Rail-to-Rail Input and Output Operational Amplifier, 5-pin SC-70, Pb-Free |  |
